# T6G (Grand Teton) — schematic netlist excerpt (pin names and nets, part order shuffled) for the footprints in the layout excerpt that follows; sources: Cadence DE-HDL packaged netlist, KiCad conversion of 04192023_DAF0TMB3IC0_F0TG_MB_C_brd_V02_OCP.brd

C660  Q_CAP  1UF 4V 20% X6S  pkg 0201  page 290 : A = P0V9_CPU0_RT1_2A ; B = GND
C983  Q_CAP  1UF 4V 20% X6S  pkg 0201  page 301 : A = P0V9_CPU0_RT2_2A ; B = GND
R360  Q_RES  1K 1% CHIP  pkg 0402LF  page 161 : A = PVDD11_S3_P0 ; B = SMB_APML_CPU0_SDA
C632  Q_CAP  100UF 4V 20% X6S  pkg C0805  page 290 : A = P0V9_CPU0_RT_2D ; B = GND

(kicad_pcb
	(version 20260206)
	(generator "pcbnew")
	(generator_version "10.0")
	(general
		(thickness 1.6)
		(legacy_teardrops no)
	)
	(paper "A4")
	(title_block
		(title "04192023_DAF0TMB3IC0_F0TG_MB_C_brd_V02_OCP.brd")
		(comment 1 "Grand Teton / footprints 5396-5399 of 8354")
	)
	(layers
		(0 "F.Cu" signal "TOP")
		(4 "In1.Cu" signal "GND")
		(6 "In2.Cu" signal "IN1")
		(8 "In3.Cu" signal "GND1")
		(10 "In4.Cu" signal "IN2")
		(12 "In5.Cu" signal "GND2")
		(14 "In6.Cu" signal "IN3")
		(16 "In7.Cu" signal "GND3")
		(18 "In8.Cu" signal "VCC")
		(20 "In9.Cu" signal "VCC1")
		(22 "In10.Cu" signal "GND4")
		(24 "In11.Cu" signal "IN4")
		(26 "In12.Cu" signal "GND5")
		(28 "In13.Cu" signal "IN5")
		(30 "In14.Cu" signal "GND6")
		(32 "In15.Cu" signal "IN6")
		(34 "In16.Cu" signal "GND7")
		(2 "B.Cu" signal "BOTTOM")
		(9 "F.Adhes" user "F.Adhesive")
		(11 "B.Adhes" user "B.Adhesive")
		(13 "F.Paste" user "Package Geometry/Pastemask Top")
		(15 "B.Paste" user "Package Geometry/Pastemask Bottom")
		(5 "F.SilkS" user "Ref Des/Silkscreen Top")
		(7 "B.SilkS" user "Ref Des/Silkscreen Bottom")
		(1 "F.Mask" user "Board Geometry/Soldermask Top")
		(3 "B.Mask" user "Board Geometry/Soldermask Bottom")
		(17 "Dwgs.User" user "User.Drawings")
		(19 "Cmts.User" user "User.Comments")
		(21 "Eco1.User" user "User.Eco1")
		(23 "Eco2.User" user "User.Eco2")
		(25 "Edge.Cuts" user "Board Geometry/Outline")
		(27 "Margin" user)
		(31 "F.CrtYd" user "Package Geometry/Place Bound Top")
		(29 "B.CrtYd" user "Package Geometry/Place Bound Bottom")
		(35 "F.Fab" user "Ref Des/Assembly Top")
		(33 "B.Fab" user "Ref Des/Assembly Bottom")
	)
	(footprint ""
		(layer "B.Cu")
		(at 403.006306 -395.148562 90)
		(property "Reference" "C983"
			(at 0 0 90)
			(layer "B.SilkS")
			(hide yes)
			(effects
				(font
					(size 1.27 1.27)
				)
				(justify mirror)
			)
		)
		(property "Value" ""
			(at 0 0 90)
			(layer "B.Fab")
			(effects
				(font
					(size 1.27 1.27)
				)
				(justify mirror)
			)
		)
		(duplicate_pad_numbers_are_jumpers no)
		(fp_line
			(start 0.299974 -0.150114)
			(end -0.299974 -0.150114)
			(stroke
				(width 0.1)
				(type default)
			)
			(layer "B.Fab")
		)
		(fp_line
			(start -0.299974 -0.150114)
			(end -0.299974 0.150114)
			(stroke
				(width 0.1)
				(type default)
			)
			(layer "B.Fab")
		)
		(fp_line
			(start 0.299974 0.150114)
			(end 0.299974 -0.150114)
			(stroke
				(width 0.1)
				(type default)
			)
			(layer "B.Fab")
		)
		(fp_line
			(start -0.299974 0.150114)
			(end 0.299974 0.150114)
			(stroke
				(width 0.1)
				(type default)
			)
			(layer "B.Fab")
		)
		(pad "1" smd rect
			(at 0.2667 0 270)
			(size 0.3048 0.381)
			(layers "B.Cu" "B.Mask" "B.Paste")
			(net "P0V9_CPU0_RT2_2A")
		)
		(pad "2" smd rect
			(at -0.2667 0 270)
			(size 0.3048 0.381)
			(layers "B.Cu" "B.Mask" "B.Paste")
			(net "GND")
		)
	)
	(footprint ""
		(layer "B.Cu")
		(at 328.462386 -398.055084 90)
		(property "Reference" "C632"
			(at 0 0 90)
			(layer "B.SilkS")
			(hide yes)
			(effects
				(font
					(size 1.27 1.27)
				)
				(justify mirror)
			)
		)
		(property "Value" ""
			(at 0 0 90)
			(layer "B.Fab")
			(effects
				(font
					(size 1.27 1.27)
				)
				(justify mirror)
			)
		)
		(duplicate_pad_numbers_are_jumpers no)
		(fp_line
			(start 1.524 -0.762)
			(end -1.524 -0.762)
			(stroke
				(width 0.1524)
				(type default)
			)
			(layer "B.SilkS")
		)
		(fp_line
			(start -1.524 -0.762)
			(end -1.524 0.762)
			(stroke
				(width 0.1524)
				(type default)
			)
			(layer "B.SilkS")
		)
		(fp_line
			(start 1.524 0.762)
			(end 1.524 -0.762)
			(stroke
				(width 0.1524)
				(type default)
			)
			(layer "B.SilkS")
		)
		(fp_line
			(start -1.524 0.762)
			(end 1.524 0.762)
			(stroke
				(width 0.1524)
				(type default)
			)
			(layer "B.SilkS")
		)
		(fp_line
			(start 1.1049 -0.724916)
			(end 1.1049 0.724916)
			(stroke
				(width 0.1)
				(type default)
			)
			(layer "B.Fab")
		)
		(fp_line
			(start -1.1049 -0.724916)
			(end 1.1049 -0.724916)
			(stroke
				(width 0.1)
				(type default)
			)
			(layer "B.Fab")
		)
		(fp_line
			(start 1.1049 0.724916)
			(end -1.1049 0.724916)
			(stroke
				(width 0.1)
				(type default)
			)
			(layer "B.Fab")
		)
		(fp_line
			(start -1.1049 0.724916)
			(end -1.1049 -0.724916)
			(stroke
				(width 0.1)
				(type default)
			)
			(layer "B.Fab")
		)
		(pad "1" smd rect
			(at 0.889 0 90)
			(size 1.016 1.27)
			(layers "B.Cu" "B.Mask" "B.Paste")
			(net "P0V9_CPU0_RT_2D")
		)
		(pad "2" smd rect
			(at -0.889 0 90)
			(size 1.016 1.27)
			(layers "B.Cu" "B.Mask" "B.Paste")
			(net "GND")
		)
	)
	(footprint ""
		(layer "B.Cu")
		(at 335.90611 -395.148562 90)
		(property "Reference" "C660"
			(at 0 0 90)
			(layer "B.SilkS")
			(hide yes)
			(effects
				(font
					(size 1.27 1.27)
				)
				(justify mirror)
			)
		)
		(property "Value" ""
			(at 0 0 90)
			(layer "B.Fab")
			(effects
				(font
					(size 1.27 1.27)
				)
				(justify mirror)
			)
		)
		(duplicate_pad_numbers_are_jumpers no)
		(fp_line
			(start 0.299974 -0.150114)
			(end -0.299974 -0.150114)
			(stroke
				(width 0.1)
				(type default)
			)
			(layer "B.Fab")
		)
		(fp_line
			(start -0.299974 -0.150114)
			(end -0.299974 0.150114)
			(stroke
				(width 0.1)
				(type default)
			)
			(layer "B.Fab")
		)
		(fp_line
			(start 0.299974 0.150114)
			(end 0.299974 -0.150114)
			(stroke
				(width 0.1)
				(type default)
			)
			(layer "B.Fab")
		)
		(fp_line
			(start -0.299974 0.150114)
			(end 0.299974 0.150114)
			(stroke
				(width 0.1)
				(type default)
			)
			(layer "B.Fab")
		)
		(pad "1" smd rect
			(at 0.2667 0 270)
			(size 0.3048 0.381)
			(layers "B.Cu" "B.Mask" "B.Paste")
			(net "P0V9_CPU0_RT1_2A")
		)
		(pad "2" smd rect
			(at -0.2667 0 270)
			(size 0.3048 0.381)
			(layers "B.Cu" "B.Mask" "B.Paste")
			(net "GND")
		)
	)
	(footprint ""
		(layer "B.Cu")
		(at 237.617 -247.269)
		(property "Reference" "R360"
			(at 0 0 0)
			(layer "B.SilkS")
			(hide yes)
			(effects
				(font
					(size 1.27 1.27)
				)
				(justify mirror)
			)
		)
		(property "Value" ""
			(at 0 0 0)
			(layer "B.Fab")
			(effects
				(font
					(size 1.27 1.27)
				)
				(justify mirror)
			)
		)
		(duplicate_pad_numbers_are_jumpers no)
		(fp_line
			(start -0.7874 -0.4064)
			(end -0.7874 0.4064)
			(stroke
				(width 0.1524)
				(type default)
			)
			(layer "B.SilkS")
		)
		(fp_line
			(start -0.7874 0.4064)
			(end 0.7874 0.4064)
			(stroke
				(width 0.1524)
				(type default)
			)
			(layer "B.SilkS")
		)
		(fp_line
			(start 0.7874 -0.4064)
			(end -0.7874 -0.4064)
			(stroke
				(width 0.1524)
				(type default)
			)
			(layer "B.SilkS")
		)
		(fp_line
			(start 0.7874 0.4064)
			(end 0.7874 -0.4064)
			(stroke
				(width 0.1524)
				(type default)
			)
			(layer "B.SilkS")
		)
		(fp_line
			(start -0.67945 -0.3048)
			(end -0.67945 0.3048)
			(stroke
				(width 0.1)
				(type default)
			)
			(layer "B.Fab")
		)
		(fp_line
			(start -0.67945 0.3048)
			(end -0.120396 0.3048)
			(stroke
				(width 0.1)
				(type default)
			)
			(layer "B.Fab")
		)
		(fp_line
			(start -0.12065 -0.3048)
			(end -0.67945 -0.3048)
			(stroke
				(width 0.1)
				(type default)
			)
			(layer "B.Fab")
		)
		(fp_line
			(start -0.12065 -0.2794)
			(end -0.12065 -0.3048)
			(stroke
				(width 0.1)
				(type default)
			)
			(layer "B.Fab")
		)
		(fp_line
			(start -0.120396 0.2794)
			(end 0.12065 0.2794)
			(stroke
				(width 0.1)
				(type default)
			)
			(layer "B.Fab")
		)
		(fp_line
			(start -0.120396 0.3048)
			(end -0.120396 0.2794)
			(stroke
				(width 0.1)
				(type default)
			)
			(layer "B.Fab")
		)
		(fp_line
			(start 0.12065 -0.305054)
			(end 0.12065 -0.2794)
			(stroke
				(width 0.1)
				(type default)
			)
			(layer "B.Fab")
		)
		(fp_line
			(start 0.12065 -0.2794)
			(end -0.12065 -0.2794)
			(stroke
				(width 0.1)
				(type default)
			)
			(layer "B.Fab")
		)
		(fp_line
			(start 0.12065 0.2794)
			(end 0.12065 0.3048)
			(stroke
				(width 0.1)
				(type default)
			)
			(layer "B.Fab")
		)
		(fp_line
			(start 0.12065 0.3048)
			(end 0.67945 0.3048)
			(stroke
				(width 0.1)
				(type default)
			)
			(layer "B.Fab")
		)
		(fp_line
			(start 0.67945 -0.305054)
			(end 0.12065 -0.305054)
			(stroke
				(width 0.1)
				(type default)
			)
			(layer "B.Fab")
		)
		(fp_line
			(start 0.67945 0.3048)
			(end 0.67945 -0.305054)
			(stroke
				(width 0.1)
				(type default)
			)
			(layer "B.Fab")
		)
		(pad "1" smd circle
			(at 0.40005 0 180)
			(size 0 0)
			(layers "B.Cu" "B.Mask" "B.Paste")
			(net "PVDD11_S3_P0")
		)
		(pad "2" smd circle
			(at -0.40005 0 180)
			(size 0 0)
			(layers "B.Cu" "B.Mask" "B.Paste")
			(net "SMB_APML_CPU0_SDA")
		)
	)
)
